(kicad_pcb
	(version 20260206)
	(generator "pcbnew")
	(generator_version "10.0")
	(general
		(thickness 1.6)
		(legacy_teardrops no)
	)
	(paper "A4")
	(title_block
		(title "baseboard — 13948-1b.1110WZS1818.brd")
		(comment 1 "Honey Badger (Wiwynn) / footprints 1412-1419 of 2523")
	)
	(layers
		(0 "F.Cu" signal "TOP")
		(4 "In1.Cu" signal "L2GND")
		(6 "In2.Cu" signal "L3")
		(8 "In3.Cu" signal "L4VCC")
		(10 "In4.Cu" signal "L5VCC")
		(12 "In5.Cu" signal "L6")
		(14 "In6.Cu" signal "L7GND")
		(2 "B.Cu" signal "BOTTOM")
		(9 "F.Adhes" user "F.Adhesive")
		(11 "B.Adhes" user "B.Adhesive")
		(13 "F.Paste" user "Package Geometry/Pastemask Top")
		(15 "B.Paste" user "Package Geometry/Pastemask Bottom")
		(5 "F.SilkS" user "Ref Des/Silkscreen Top")
		(7 "B.SilkS" user "Ref Des/Silkscreen Bottom")
		(1 "F.Mask" user "Board Geometry/Soldermask Top")
		(3 "B.Mask" user "Board Geometry/Soldermask Bottom")
		(17 "Dwgs.User" user "User.Drawings")
		(19 "Cmts.User" user "User.Comments")
		(21 "Eco1.User" user "User.Eco1")
		(23 "Eco2.User" user "User.Eco2")
		(25 "Edge.Cuts" user "Board Geometry/Outline")
		(27 "Margin" user)
		(31 "F.CrtYd" user "Package Geometry/Place Bound Top")
		(29 "B.CrtYd" user "Package Geometry/Place Bound Bottom")
		(35 "F.Fab" user "Ref Des/Assembly Top")
		(33 "B.Fab" user "Ref Des/Assembly Bottom")
	)
	(footprint ""
		(layer "F.Cu")
		(at 86.614 -24.384)
		(property "Reference" "PR181"
			(at 0 0 0)
			(layer "F.SilkS")
			(hide yes)
			(effects
				(font
					(size 1.27 1.27)
				)
			)
		)
		(property "Value" "19K1R2F-GP"
			(at 0.064008 -3.993896 0)
			(unlocked yes)
			(layer "F.Fab")
			(hide yes)
			(effects
				(font
					(size 1.016 1.016)
					(thickness 0.1524)
				)
			)
		)
		(property "Device Type" "R402H16"
			(at 0.064008 -5.517896 0)
			(unlocked yes)
			(layer "F.Fab")
			(hide yes)
			(effects
				(font
					(size 1.016 1.016)
					(thickness 0.1524)
				)
			)
		)
		(duplicate_pad_numbers_are_jumpers no)
		(fp_line
			(start -0.508 -0.9398)
			(end -0.508 0.9398)
			(stroke
				(width 0.1524)
				(type default)
			)
			(layer "F.SilkS")
		)
		(fp_line
			(start 0.508 -0.9398)
			(end -0.508 -0.9398)
			(stroke
				(width 0.1524)
				(type default)
			)
			(layer "F.SilkS")
		)
		(fp_rect
			(start -0.508 0.9398)
			(end 0.508 -0.9398)
			(stroke
				(width 0)
				(type default)
			)
			(fill no)
			(layer "F.CrtYd")
		)
		(fp_rect
			(start -0.508 0.9398)
			(end 0.508 -0.9398)
			(stroke
				(width 0)
				(type default)
			)
			(fill no)
			(layer "F.Fab")
		)
		(pad "1" smd custom
			(at 0 -0.4445)
			(size 0.1397 0.1397)
			(layers "F.Cu" "F.Mask" "F.Paste")
			(net "P0V955_C")
			(options
				(clearance outline)
				(anchor circle)
			)
			(primitives
				(gr_poly
					(pts
						(arc
							(start -0.1778 -0.2794)
							(mid -0.249642 -0.249642)
							(end -0.2794 -0.1778)
						)
						(arc
							(start -0.2794 0.1778)
							(mid -0.249642 0.249642)
							(end -0.1778 0.2794)
						)
						(arc
							(start 0.1778 0.2794)
							(mid 0.249642 0.249642)
							(end 0.2794 0.1778)
						)
						(arc
							(start 0.2794 -0.1778)
							(mid 0.249642 -0.249642)
							(end 0.1778 -0.2794)
						)
					)
					(width 0)
					(fill yes)
				)
			)
		)
		(pad "2" smd custom
			(at 0 0.4445)
			(size 0.1397 0.1397)
			(layers "F.Cu" "F.Mask" "F.Paste")
			(net "VT235_PGIN")
			(options
				(clearance outline)
				(anchor circle)
			)
			(primitives
				(gr_poly
					(pts
						(arc
							(start -0.1778 -0.2794)
							(mid -0.249642 -0.249642)
							(end -0.2794 -0.1778)
						)
						(arc
							(start -0.2794 0.1778)
							(mid -0.249642 0.249642)
							(end -0.1778 0.2794)
						)
						(arc
							(start 0.1778 0.2794)
							(mid 0.249642 0.249642)
							(end 0.2794 0.1778)
						)
						(arc
							(start 0.2794 -0.1778)
							(mid 0.249642 -0.249642)
							(end 0.1778 -0.2794)
						)
					)
					(width 0)
					(fill yes)
				)
			)
		)
	)
	(footprint ""
		(layer "F.Cu")
		(at 88.138 -29.064966)
		(property "Reference" "SR586"
			(at 0 0 0)
			(layer "F.SilkS")
			(hide yes)
			(effects
				(font
					(size 1.27 1.27)
				)
			)
		)
		(property "Value" "51R2F-2-GP"
			(at 0.064008 -3.993896 0)
			(unlocked yes)
			(layer "F.Fab")
			(hide yes)
			(effects
				(font
					(size 1.016 1.016)
					(thickness 0.1524)
				)
			)
		)
		(property "Device Type" "R402H16"
			(at 0.064008 -5.517896 0)
			(unlocked yes)
			(layer "F.Fab")
			(hide yes)
			(effects
				(font
					(size 1.016 1.016)
					(thickness 0.1524)
				)
			)
		)
		(duplicate_pad_numbers_are_jumpers no)
		(fp_line
			(start -0.508 -0.9398)
			(end -0.508 0.9398)
			(stroke
				(width 0.1524)
				(type default)
			)
			(layer "F.SilkS")
		)
		(fp_line
			(start 0.508 -0.9398)
			(end -0.508 -0.9398)
			(stroke
				(width 0.1524)
				(type default)
			)
			(layer "F.SilkS")
		)
		(fp_rect
			(start -0.508 0.9398)
			(end 0.508 -0.9398)
			(stroke
				(width 0)
				(type default)
			)
			(fill no)
			(layer "F.CrtYd")
		)
		(fp_rect
			(start -0.508 0.9398)
			(end 0.508 -0.9398)
			(stroke
				(width 0)
				(type default)
			)
			(fill no)
			(layer "F.Fab")
		)
		(pad "1" smd custom
			(at 0 -0.4445)
			(size 0.1397 0.1397)
			(layers "F.Cu" "F.Mask" "F.Paste")
			(net "CK_100M_EXP_SAS")
			(options
				(clearance outline)
				(anchor circle)
			)
			(primitives
				(gr_poly
					(pts
						(arc
							(start -0.1778 -0.2794)
							(mid -0.249642 -0.249642)
							(end -0.2794 -0.1778)
						)
						(arc
							(start -0.2794 0.1778)
							(mid -0.249642 0.249642)
							(end -0.1778 0.2794)
						)
						(arc
							(start 0.1778 0.2794)
							(mid 0.249642 0.249642)
							(end 0.2794 0.1778)
						)
						(arc
							(start 0.2794 -0.1778)
							(mid 0.249642 -0.249642)
							(end 0.1778 -0.2794)
						)
					)
					(width 0)
					(fill yes)
				)
			)
		)
		(pad "2" smd custom
			(at 0 0.4445)
			(size 0.1397 0.1397)
			(layers "F.Cu" "F.Mask" "F.Paste")
			(net "CLK_100M_PCIE_N")
			(options
				(clearance outline)
				(anchor circle)
			)
			(primitives
				(gr_poly
					(pts
						(arc
							(start -0.1778 -0.2794)
							(mid -0.249642 -0.249642)
							(end -0.2794 -0.1778)
						)
						(arc
							(start -0.2794 0.1778)
							(mid -0.249642 0.249642)
							(end -0.1778 0.2794)
						)
						(arc
							(start 0.1778 0.2794)
							(mid 0.249642 0.249642)
							(end 0.2794 0.1778)
						)
						(arc
							(start 0.2794 -0.1778)
							(mid 0.249642 -0.249642)
							(end 0.1778 -0.2794)
						)
					)
					(width 0)
					(fill yes)
				)
			)
		)
	)
	(footprint ""
		(layer "F.Cu")
		(at 327.406 -94.234 -90)
		(property "Reference" "PC40"
			(at 0 0 270)
			(layer "F.SilkS")
			(hide yes)
			(effects
				(font
					(size 1.27 1.27)
				)
			)
		)
		(property "Value" "SC100U6D3V6MX-GP"
			(at -0.0762 -5.1308 270)
			(unlocked yes)
			(layer "F.Fab")
			(hide yes)
			(effects
				(font
					(size 1.016 1.016)
					(thickness 0.1524)
				)
			)
		)
		(property "Device Type" "C1206H71"
			(at -0.127 -6.6548 270)
			(unlocked yes)
			(layer "F.Fab")
			(hide yes)
			(effects
				(font
					(size 1.016 1.016)
					(thickness 0.1524)
				)
			)
		)
		(duplicate_pad_numbers_are_jumpers no)
		(fp_line
			(start -1.016 2.2352)
			(end -1.016 0.8382)
			(stroke
				(width 0.1524)
				(type default)
			)
			(layer "F.SilkS")
		)
		(fp_line
			(start 1.016 2.2352)
			(end -1.016 2.2352)
			(stroke
				(width 0.1524)
				(type default)
			)
			(layer "F.SilkS")
		)
		(fp_line
			(start 1.016 0.8382)
			(end 1.016 2.2352)
			(stroke
				(width 0.1524)
				(type default)
			)
			(layer "F.SilkS")
		)
		(fp_line
			(start -1.016 -0.8382)
			(end -1.016 -2.2352)
			(stroke
				(width 0.1524)
				(type default)
			)
			(layer "F.SilkS")
		)
		(fp_line
			(start -1.016 -2.2352)
			(end 1.016 -2.2352)
			(stroke
				(width 0.1524)
				(type default)
			)
			(layer "F.SilkS")
		)
		(fp_line
			(start 1.016 -2.2352)
			(end 1.016 -0.8382)
			(stroke
				(width 0.1524)
				(type default)
			)
			(layer "F.SilkS")
		)
		(fp_rect
			(start -1.0922 2.3114)
			(end 1.0922 -2.3114)
			(stroke
				(width 0)
				(type default)
			)
			(fill no)
			(layer "F.CrtYd")
		)
		(fp_poly
			(pts
				(xy 1.0922 -2.3114) (xy 1.0922 2.3114) (xy -1.0922 2.3114) (xy -1.0922 -2.3114)
			)
			(stroke
				(width 0)
				(type default)
			)
			(fill no)
			(layer "F.Fab")
		)
		(pad "1" smd rect
			(at 0 -1.397 270)
			(size 1.651 1.27)
			(layers "F.Cu" "F.Mask" "F.Paste")
			(net "P3V3_STBY")
		)
		(pad "2" smd rect
			(at 0 1.397 270)
			(size 1.651 1.27)
			(layers "F.Cu" "F.Mask" "F.Paste")
			(net "GND")
		)
	)
	(footprint ""
		(layer "F.Cu")
		(at 317.5 -109.601 -90)
		(property "Reference" "PR37"
			(at 0 0 270)
			(layer "F.SilkS")
			(hide yes)
			(effects
				(font
					(size 1.27 1.27)
				)
			)
		)
		(property "Value" "10KR2F-2-GP"
			(at 0.064008 -3.993896 270)
			(unlocked yes)
			(layer "F.Fab")
			(hide yes)
			(effects
				(font
					(size 1.016 1.016)
					(thickness 0.1524)
				)
			)
		)
		(property "Device Type" "R402H16"
			(at 0.064008 -5.517896 270)
			(unlocked yes)
			(layer "F.Fab")
			(hide yes)
			(effects
				(font
					(size 1.016 1.016)
					(thickness 0.1524)
				)
			)
		)
		(duplicate_pad_numbers_are_jumpers no)
		(fp_line
			(start -0.508 -0.9398)
			(end -0.508 0.9398)
			(stroke
				(width 0.1524)
				(type default)
			)
			(layer "F.SilkS")
		)
		(fp_line
			(start 0.508 -0.9398)
			(end -0.508 -0.9398)
			(stroke
				(width 0.1524)
				(type default)
			)
			(layer "F.SilkS")
		)
		(fp_rect
			(start -0.508 0.9398)
			(end 0.508 -0.9398)
			(stroke
				(width 0)
				(type default)
			)
			(fill no)
			(layer "F.CrtYd")
		)
		(fp_rect
			(start -0.508 0.9398)
			(end 0.508 -0.9398)
			(stroke
				(width 0)
				(type default)
			)
			(fill no)
			(layer "F.Fab")
		)
		(pad "1" smd custom
			(at 0 -0.4445 270)
			(size 0.1397 0.1397)
			(layers "F.Cu" "F.Mask" "F.Paste")
			(net "P3V3_STBY_VFB")
			(options
				(clearance outline)
				(anchor circle)
			)
			(primitives
				(gr_poly
					(pts
						(arc
							(start -0.1778 -0.2794)
							(mid -0.249642 -0.249642)
							(end -0.2794 -0.1778)
						)
						(arc
							(start -0.2794 0.1778)
							(mid -0.249642 0.249642)
							(end -0.1778 0.2794)
						)
						(arc
							(start 0.1778 0.2794)
							(mid 0.249642 0.249642)
							(end 0.2794 0.1778)
						)
						(arc
							(start 0.2794 -0.1778)
							(mid 0.249642 -0.249642)
							(end 0.1778 -0.2794)
						)
					)
					(width 0)
					(fill yes)
				)
			)
		)
		(pad "2" smd custom
			(at 0 0.4445 270)
			(size 0.1397 0.1397)
			(layers "F.Cu" "F.Mask" "F.Paste")
			(net "AGND_P3V3_STBY")
			(options
				(clearance outline)
				(anchor circle)
			)
			(primitives
				(gr_poly
					(pts
						(arc
							(start -0.1778 -0.2794)
							(mid -0.249642 -0.249642)
							(end -0.2794 -0.1778)
						)
						(arc
							(start -0.2794 0.1778)
							(mid -0.249642 0.249642)
							(end -0.1778 0.2794)
						)
						(arc
							(start 0.1778 0.2794)
							(mid 0.249642 0.249642)
							(end 0.2794 0.1778)
						)
						(arc
							(start 0.2794 -0.1778)
							(mid 0.249642 -0.249642)
							(end 0.1778 -0.2794)
						)
					)
					(width 0)
					(fill yes)
				)
			)
		)
	)
	(footprint ""
		(layer "F.Cu")
		(at 262.182864 -231.004872)
		(property "Reference" "PR89"
			(at 0 0 0)
			(layer "F.SilkS")
			(hide yes)
			(effects
				(font
					(size 1.27 1.27)
				)
			)
		)
		(property "Value" "2K7R2J-GP"
			(at 0.064008 -3.993896 0)
			(unlocked yes)
			(layer "F.Fab")
			(hide yes)
			(effects
				(font
					(size 1.016 1.016)
					(thickness 0.1524)
				)
			)
		)
		(property "Device Type" "R402H16"
			(at 0.064008 -5.517896 0)
			(unlocked yes)
			(layer "F.Fab")
			(hide yes)
			(effects
				(font
					(size 1.016 1.016)
					(thickness 0.1524)
				)
			)
		)
		(duplicate_pad_numbers_are_jumpers no)
		(fp_line
			(start -0.508 -0.9398)
			(end -0.508 0.9398)
			(stroke
				(width 0.1524)
				(type default)
			)
			(layer "F.SilkS")
		)
		(fp_line
			(start 0.508 -0.9398)
			(end -0.508 -0.9398)
			(stroke
				(width 0.1524)
				(type default)
			)
			(layer "F.SilkS")
		)
		(fp_rect
			(start -0.508 0.9398)
			(end 0.508 -0.9398)
			(stroke
				(width 0)
				(type default)
			)
			(fill no)
			(layer "F.CrtYd")
		)
		(fp_rect
			(start -0.508 0.9398)
			(end 0.508 -0.9398)
			(stroke
				(width 0)
				(type default)
			)
			(fill no)
			(layer "F.Fab")
		)
		(pad "1" smd custom
			(at 0 -0.4445)
			(size 0.1397 0.1397)
			(layers "F.Cu" "F.Mask" "F.Paste")
			(net "P3V3_STBY")
			(options
				(clearance outline)
				(anchor circle)
			)
			(primitives
				(gr_poly
					(pts
						(arc
							(start -0.1778 -0.2794)
							(mid -0.249642 -0.249642)
							(end -0.2794 -0.1778)
						)
						(arc
							(start -0.2794 0.1778)
							(mid -0.249642 0.249642)
							(end -0.1778 0.2794)
						)
						(arc
							(start 0.1778 0.2794)
							(mid 0.249642 0.249642)
							(end 0.2794 0.1778)
						)
						(arc
							(start 0.2794 -0.1778)
							(mid 0.249642 -0.249642)
							(end 0.1778 -0.2794)
						)
					)
					(width 0)
					(fill yes)
				)
			)
		)
		(pad "2" smd custom
			(at 0 0.4445)
			(size 0.1397 0.1397)
			(layers "F.Cu" "F.Mask" "F.Paste")
			(net "P1V26_STBY_PG")
			(options
				(clearance outline)
				(anchor circle)
			)
			(primitives
				(gr_poly
					(pts
						(arc
							(start -0.1778 -0.2794)
							(mid -0.249642 -0.249642)
							(end -0.2794 -0.1778)
						)
						(arc
							(start -0.2794 0.1778)
							(mid -0.249642 0.249642)
							(end -0.1778 0.2794)
						)
						(arc
							(start 0.1778 0.2794)
							(mid 0.249642 0.249642)
							(end 0.2794 0.1778)
						)
						(arc
							(start 0.2794 -0.1778)
							(mid 0.249642 -0.249642)
							(end 0.1778 -0.2794)
						)
					)
					(width 0)
					(fill yes)
				)
			)
		)
	)
	(footprint ""
		(layer "F.Cu")
		(at 165.1 -116.078 90)
		(property "Reference" "PC189"
			(at 0 0 90)
			(layer "F.SilkS")
			(hide yes)
			(effects
				(font
					(size 1.27 1.27)
				)
			)
		)
		(property "Value" "SC1KP50V2KX-1GP"
			(at 1.1811 -2.7051 90)
			(unlocked yes)
			(layer "F.Fab")
			(hide yes)
			(effects
				(font
					(size 1.016 1.016)
					(thickness 0.1524)
				)
			)
		)
		(property "Device Type" "C402H22"
			(at 1.1811 -4.2291 90)
			(unlocked yes)
			(layer "F.Fab")
			(hide yes)
			(effects
				(font
					(size 1.016 1.016)
					(thickness 0.1524)
				)
			)
		)
		(duplicate_pad_numbers_are_jumpers no)
		(fp_rect
			(start -0.4318 0.9525)
			(end 0.4318 -0.9525)
			(stroke
				(width 0)
				(type default)
			)
			(fill no)
			(layer "F.CrtYd")
		)
		(fp_rect
			(start -0.4318 0.9525)
			(end 0.4318 -0.9525)
			(stroke
				(width 0)
				(type default)
			)
			(fill no)
			(layer "F.Fab")
		)
		(pad "1" smd custom
			(at 0 -0.4445 90)
			(size 0.1524 0.1524)
			(layers "F.Cu" "F.Mask" "F.Paste")
			(net "P0V9_E_SW_R")
			(options
				(clearance outline)
				(anchor circle)
			)
			(primitives
				(gr_poly
					(pts
						(arc
							(start 0.3048 -0.2032)
							(mid 0.275042 -0.275042)
							(end 0.2032 -0.3048)
						)
						(arc
							(start -0.2032 -0.3048)
							(mid -0.275042 -0.275042)
							(end -0.3048 -0.2032)
						)
						(arc
							(start -0.3048 0.2032)
							(mid -0.275042 0.275042)
							(end -0.2032 0.3048)
						)
						(arc
							(start 0.2032 0.3048)
							(mid 0.275042 0.275042)
							(end 0.3048 0.2032)
						)
					)
					(width 0)
					(fill yes)
				)
			)
		)
		(pad "2" smd custom
			(at 0 0.4445 90)
			(size 0.1524 0.1524)
			(layers "F.Cu" "F.Mask" "F.Paste")
			(net "P0V9_E_VFB")
			(options
				(clearance outline)
				(anchor circle)
			)
			(primitives
				(gr_poly
					(pts
						(arc
							(start 0.3048 -0.2032)
							(mid 0.275042 -0.275042)
							(end 0.2032 -0.3048)
						)
						(arc
							(start -0.2032 -0.3048)
							(mid -0.275042 -0.275042)
							(end -0.3048 -0.2032)
						)
						(arc
							(start -0.3048 0.2032)
							(mid -0.275042 0.275042)
							(end -0.2032 0.3048)
						)
						(arc
							(start 0.2032 0.3048)
							(mid 0.275042 0.275042)
							(end 0.3048 0.2032)
						)
					)
					(width 0)
					(fill yes)
				)
			)
		)
	)
	(footprint ""
		(layer "F.Cu")
		(at 203.917296 -86.372192)
		(property "Reference" "SL11"
			(at 0 0 0)
			(layer "F.SilkS")
			(hide yes)
			(effects
				(font
					(size 1.27 1.27)
				)
			)
		)
		(property "Value" "MPZ2012S300AT-GP"
			(at 0 -4.2418 0)
			(unlocked yes)
			(layer "F.Fab")
			(hide yes)
			(effects
				(font
					(size 1.016 1.016)
					(thickness 0.1524)
				)
			)
		)
		(property "Device Type" "L805H42"
			(at 0 -5.7912 0)
			(unlocked yes)
			(layer "F.Fab")
			(hide yes)
			(effects
				(font
					(size 1.016 1.016)
					(thickness 0.1524)
				)
			)
		)
		(duplicate_pad_numbers_are_jumpers no)
		(fp_line
			(start -0.889 -1.7018)
			(end 0.889 -1.7018)
			(stroke
				(width 0.1524)
				(type default)
			)
			(layer "F.SilkS")
		)
		(fp_line
			(start -0.889 1.7018)
			(end -0.889 -1.7018)
			(stroke
				(width 0.1524)
				(type default)
			)
			(layer "F.SilkS")
		)
		(fp_line
			(start 0.889 -1.7018)
			(end 0.889 1.7018)
			(stroke
				(width 0.1524)
				(type default)
			)
			(layer "F.SilkS")
		)
		(fp_line
			(start 0.889 1.7018)
			(end -0.889 1.7018)
			(stroke
				(width 0.1524)
				(type default)
			)
			(layer "F.SilkS")
		)
		(fp_rect
			(start -0.9652 1.778)
			(end 0.9652 -1.778)
			(stroke
				(width 0)
				(type default)
			)
			(fill no)
			(layer "F.CrtYd")
		)
		(fp_rect
			(start -0.9652 1.778)
			(end 0.9652 -1.778)
			(stroke
				(width 0)
				(type default)
			)
			(fill no)
			(layer "F.Fab")
		)
		(pad "1" smd rect
			(at 0 -0.9652)
			(size 1.397 1.143)
			(layers "F.Cu" "F.Mask" "F.Paste")
			(net "P1V5_E")
		)
		(pad "2" smd rect
			(at 0 0.9652)
			(size 1.397 1.143)
			(layers "F.Cu" "F.Mask" "F.Paste")
			(net "GB_VDDH2")
		)
	)
	(footprint ""
		(layer "F.Cu")
		(at 91.739212 -249.936)
		(property "Reference" "R150"
			(at 0 0 0)
			(layer "F.SilkS")
			(hide yes)
			(effects
				(font
					(size 1.27 1.27)
				)
			)
		)
		(property "Value" "0R2J-2-GP"
			(at 0.064008 -3.993896 0)
			(unlocked yes)
			(layer "F.Fab")
			(hide yes)
			(effects
				(font
					(size 1.016 1.016)
					(thickness 0.1524)
				)
			)
		)
		(property "Device Type" "R402H16"
			(at 0.064008 -5.517896 0)
			(unlocked yes)
			(layer "F.Fab")
			(hide yes)
			(effects
				(font
					(size 1.016 1.016)
					(thickness 0.1524)
				)
			)
		)
		(duplicate_pad_numbers_are_jumpers no)
		(fp_line
			(start -0.508 -0.9398)
			(end -0.508 0.9398)
			(stroke
				(width 0.1524)
				(type default)
			)
			(layer "F.SilkS")
		)
		(fp_line
			(start 0.508 -0.9398)
			(end -0.508 -0.9398)
			(stroke
				(width 0.1524)
				(type default)
			)
			(layer "F.SilkS")
		)
		(fp_rect
			(start -0.508 0.9398)
			(end 0.508 -0.9398)
			(stroke
				(width 0)
				(type default)
			)
			(fill no)
			(layer "F.CrtYd")
		)
		(fp_rect
			(start -0.508 0.9398)
			(end 0.508 -0.9398)
			(stroke
				(width 0)
				(type default)
			)
			(fill no)
			(layer "F.Fab")
		)
		(pad "1" smd custom
			(at 0 -0.4445)
			(size 0.1397 0.1397)
			(layers "F.Cu" "F.Mask" "F.Paste")
			(net "ID_I2C_ADD")
			(options
				(clearance outline)
				(anchor circle)
			)
			(primitives
				(gr_poly
					(pts
						(arc
							(start -0.1778 -0.2794)
							(mid -0.249642 -0.249642)
							(end -0.2794 -0.1778)
						)
						(arc
							(start -0.2794 0.1778)
							(mid -0.249642 0.249642)
							(end -0.1778 0.2794)
						)
						(arc
							(start 0.1778 0.2794)
							(mid 0.249642 0.249642)
							(end 0.2794 0.1778)
						)
						(arc
							(start 0.2794 -0.1778)
							(mid 0.249642 -0.249642)
							(end 0.1778 -0.2794)
						)
					)
					(width 0)
					(fill yes)
				)
			)
		)
		(pad "2" smd custom
			(at 0 0.4445)
			(size 0.1397 0.1397)
			(layers "F.Cu" "F.Mask" "F.Paste")
			(net "EXP_ID")
			(options
				(clearance outline)
				(anchor circle)
			)
			(primitives
				(gr_poly
					(pts
						(arc
							(start -0.1778 -0.2794)
							(mid -0.249642 -0.249642)
							(end -0.2794 -0.1778)
						)
						(arc
							(start -0.2794 0.1778)
							(mid -0.249642 0.249642)
							(end -0.1778 0.2794)
						)
						(arc
							(start 0.1778 0.2794)
							(mid 0.249642 0.249642)
							(end 0.2794 0.1778)
						)
						(arc
							(start 0.2794 -0.1778)
							(mid 0.249642 -0.249642)
							(end 0.1778 -0.2794)
						)
					)
					(width 0)
					(fill yes)
				)
			)
		)
	)
)
